# BASEBOARD_FAB2 (Tioga Pass) — schematic netlist excerpt (pin names and nets, part order shuffled) for the footprints in the layout excerpt that follows; sources: Cadence DE-HDL packaged netlist, KiCad conversion of Wiwynn_Tioga_Pass_MB.brd

EU4D3  IR354XX  IR35411 IC  pkg SM  page 203
  VOS  = PVCCIN_CPU0
  LGND  = GND
  VCC  = VR_PVCCIN_CPU0_PH3_VCIN
  VDRV  = P5V_STBY
  PGND(0)  = GND
  GL(0)  = TP_PVCCIN_CPU0_PH3_GL_0
  PGND(1)  = GND
  SW  = VR_PVCCIN_CPU0_PHASE3
  VIN(0)  = VR_FET_SW_P12V_STBY_PVCCIN_CPU0
  VIN(1)  = VR_FET_SW_P12V_STBY_PVCCIN_CPU0
  NC  = NC
  PHASE  = VR_PVCCIN_CPU0_PH3_PHASE
  BOOST  = VR_PVCCIN_CPU0_PH3_BOOT_R
  PWM  = VR_PVCCIN_CPU0_PWM3
  EN  = P5V_STBY
  TOUT_FLT  = A_TSENSE_PVCCIN_CPU0
  OCSET  = VR_PVCCIN_CPU0_PH3_OCSET
  IOUT  = ISENSE_PVCCIN_CPU0_PH3_IMON
  REFIN  = VR_PVCCIN_CPU0_AIREF3
  PGND(2)  = GND
  GL(1)  = TP_PVCCIN_CPU0_PH3_GL_1

C5A20  CAP  100UF 4V 20% X5R  pkg 0805  page 220 : A = PVDDQ_DEF ; B = GND

(kicad_pcb
	(version 20260206)
	(generator "pcbnew")
	(generator_version "10.0")
	(general
		(thickness 1.6)
		(legacy_teardrops no)
	)
	(paper "A4")
	(title_block
		(title "Wiwynn_Tioga_Pass_MB.brd")
		(comment 1 "Tioga Pass / footprints 347-348 of 4770")
	)
	(layers
		(0 "F.Cu" signal "TOP")
		(4 "In1.Cu" signal "L2GND")
		(6 "In2.Cu" signal "L3")
		(8 "In3.Cu" signal "L4GND")
		(10 "In4.Cu" signal "L5")
		(12 "In5.Cu" signal "L6GND")
		(14 "In6.Cu" signal "L7VCC")
		(16 "In7.Cu" signal "L8VCC")
		(18 "In8.Cu" signal "L9GND")
		(20 "In9.Cu" signal "L10")
		(22 "In10.Cu" signal "L11GND")
		(24 "In11.Cu" signal "L12")
		(26 "In12.Cu" signal "L13GND")
		(2 "B.Cu" signal "BOTTOM")
		(9 "F.Adhes" user "F.Adhesive")
		(11 "B.Adhes" user "B.Adhesive")
		(13 "F.Paste" user "Package Geometry/Pastemask Top")
		(15 "B.Paste" user "Package Geometry/Pastemask Bottom")
		(5 "F.SilkS" user "Ref Des/Silkscreen Top")
		(7 "B.SilkS" user "Ref Des/Silkscreen Bottom")
		(1 "F.Mask" user "Board Geometry/Soldermask Top")
		(3 "B.Mask" user "Board Geometry/Soldermask Bottom")
		(17 "Dwgs.User" user "User.Drawings")
		(19 "Cmts.User" user "User.Comments")
		(21 "Eco1.User" user "User.Eco1")
		(23 "Eco2.User" user "User.Eco2")
		(25 "Edge.Cuts" user "Board Geometry/Outline")
		(27 "Margin" user)
		(31 "F.CrtYd" user "Package Geometry/Place Bound Top")
		(29 "B.CrtYd" user "Package Geometry/Place Bound Bottom")
		(35 "F.Fab" user "Ref Des/Assembly Top")
		(33 "B.Fab" user "Ref Des/Assembly Bottom")
	)
	(footprint ""
		(layer "F.Cu")
		(at 259.3848 -139.954 90)
		(property "Reference" "C5A20"
			(at 0 0 90)
			(layer "F.SilkS")
			(hide yes)
			(effects
				(font
					(size 1.27 1.27)
				)
			)
		)
		(property "Value" ""
			(at 0 0 90)
			(layer "F.Fab")
			(effects
				(font
					(size 1.27 1.27)
				)
			)
		)
		(duplicate_pad_numbers_are_jumpers no)
		(fp_rect
			(start -0.7239 -0.2159)
			(end 0.7239 1.9939)
			(stroke
				(width 0)
				(type default)
			)
			(fill no)
			(layer "F.CrtYd")
		)
		(fp_line
			(start 0.7239 -0.2159)
			(end -0.7239 -0.2159)
			(stroke
				(width 0.1)
				(type default)
			)
			(layer "F.Fab")
		)
		(fp_line
			(start -0.7239 -0.2159)
			(end -0.7239 1.9939)
			(stroke
				(width 0.1)
				(type default)
			)
			(layer "F.Fab")
		)
		(fp_line
			(start 0.7239 1.9939)
			(end 0.7239 -0.2159)
			(stroke
				(width 0.1)
				(type default)
			)
			(layer "F.Fab")
		)
		(fp_line
			(start -0.7239 1.9939)
			(end 0.7239 1.9939)
			(stroke
				(width 0.1)
				(type default)
			)
			(layer "F.Fab")
		)
		(pad "1" smd rect
			(at 0 0 90)
			(size 1.27 1.016)
			(layers "F.Cu" "F.Mask" "F.Paste")
			(net "PVDDQ_DEF")
		)
		(pad "2" smd rect
			(at 0 1.778 90)
			(size 1.27 1.016)
			(layers "F.Cu" "F.Mask" "F.Paste")
			(net "GND")
		)
		(zone
			(layer "F.Cu")
			(hatch none 0.5)
			(connect_pads
				(clearance 0)
			)
			(min_thickness 0.25)
			(keepout
				(tracks not_allowed)
				(vias allowed)
				(pads allowed)
				(copperpour not_allowed)
				(footprints allowed)
			)
			(placement
				(enabled no)
				(sheetname "")
			)
			(fill
				(thermal_gap 0.5)
				(thermal_bridge_width 0.5)
				(island_removal_mode 0)
			)
			(polygon
				(pts
					(xy 259.8928 -139.319) (xy 260.6548 -139.319) (xy 260.6548 -140.589) (xy 259.8928 -140.589)
				)
			)
		)
	)
	(footprint ""
		(layer "F.Cu")
		(at 198.925434 -73.295764 90)
		(property "Reference" "EU4D3"
			(at 3.334766 -1.669034 0)
			(unlocked yes)
			(layer "F.SilkS")
			(effects
				(font
					(size 0.7874 0.5842)
					(thickness 0.1524)
				)
			)
		)
		(property "Value" ""
			(at 0 0 90)
			(layer "F.Fab")
			(effects
				(font
					(size 1.27 1.27)
				)
			)
		)
		(duplicate_pad_numbers_are_jumpers no)
		(fp_line
			(start 2.9718 -3.5052)
			(end 2.9718 3.429)
			(stroke
				(width 0.1524)
				(type default)
			)
			(layer "F.SilkS")
		)
		(fp_line
			(start -3.0099 -3.5052)
			(end 2.9718 -3.5052)
			(stroke
				(width 0.1524)
				(type default)
			)
			(layer "F.SilkS")
		)
		(fp_line
			(start 2.9718 3.429)
			(end -3.0099 3.429)
			(stroke
				(width 0.1524)
				(type default)
			)
			(layer "F.SilkS")
		)
		(fp_line
			(start -3.0099 3.429)
			(end -3.0099 -3.5052)
			(stroke
				(width 0.1524)
				(type default)
			)
			(layer "F.SilkS")
		)
		(fp_circle
			(center -3.057398 -2.678684)
			(end -3.057398 -2.551684)
			(stroke
				(width 0.254)
				(type default)
			)
			(fill no)
			(layer "F.SilkS")
		)
		(fp_poly
			(pts
				(xy -2.9972 -3.4925) (xy -2.9972 -2.6924) (xy -2.1971 -3.4925)
			)
			(stroke
				(width 0)
				(type default)
			)
			(fill yes)
			(layer "F.SilkS")
		)
		(fp_poly
			(pts
				(xy -2.549906 -3.050032) (xy -2.549906 3.050032) (xy 2.549906 3.050032) (xy 2.549906 -3.050032)
			)
			(stroke
				(width 0)
				(type default)
			)
			(fill no)
			(layer "F.CrtYd")
		)
		(fp_line
			(start 2.549906 -3.050032)
			(end 2.549906 3.050032)
			(stroke
				(width 0.1)
				(type default)
			)
			(layer "F.Fab")
		)
		(fp_line
			(start -2.549906 -3.050032)
			(end 2.549906 -3.050032)
			(stroke
				(width 0.1)
				(type default)
			)
			(layer "F.Fab")
		)
		(fp_line
			(start 2.549906 3.050032)
			(end -2.549906 3.050032)
			(stroke
				(width 0.1)
				(type default)
			)
			(layer "F.Fab")
		)
		(fp_line
			(start -2.549906 3.050032)
			(end -2.549906 -3.050032)
			(stroke
				(width 0.1)
				(type default)
			)
			(layer "F.Fab")
		)
		(fp_circle
			(center -3.057398 -2.678684)
			(end -3.057398 -2.551684)
			(stroke
				(width 0.254)
				(type default)
			)
			(fill no)
			(layer "F.Fab")
		)
		(pad "1" smd rect
			(at -2.39522 -2.279904 90)
			(size 0.7112 0.254)
			(layers "F.Cu" "F.Mask" "F.Paste")
			(net "PVCCIN_CPU0")
		)
		(pad "2" smd rect
			(at -2.39522 -1.83007 90)
			(size 0.7112 0.254)
			(layers "F.Cu" "F.Mask" "F.Paste")
			(net "GND")
		)
		(pad "3" smd rect
			(at -2.39522 -1.379982 90)
			(size 0.7112 0.254)
			(layers "F.Cu" "F.Mask" "F.Paste")
			(net "VR_PVCCIN_CPU0_PH3_VCIN")
		)
		(pad "4" smd rect
			(at -2.39522 -0.929894 90)
			(size 0.7112 0.254)
			(layers "F.Cu" "F.Mask" "F.Paste")
			(net "P5V_STBY")
		)
		(pad "5" smd rect
			(at -2.39522 -0.48006 90)
			(size 0.7112 0.254)
			(layers "F.Cu" "F.Mask" "F.Paste")
			(net "GND")
		)
		(pad "6" smd rect
			(at -2.39522 -0.029972 90)
			(size 0.7112 0.254)
			(layers "F.Cu" "F.Mask" "F.Paste")
			(net "TP_PVCCIN_CPU0_PH3_GL_0")
		)
		(pad "7" smd custom
			(at 0.016764 1.145032 90)
			(size 0.53975 0.53975)
			(layers "F.Cu" "F.Mask" "F.Paste")
			(net "GND")
			(options
				(clearance outline)
				(anchor circle)
			)
			(primitives
				(gr_poly
					(pts
						(xy -2.7051 1.0795) (xy -2.7051 -0.3683) (xy -0.9271 -0.3683) (xy -0.9271 -1.0795) (xy 2.7051 -1.0795)
						(xy 2.7051 1.0795)
					)
					(width 0)
					(fill yes)
				)
			)
		)
		(pad "10" smd rect
			(at -0.008382 2.874772 90)
			(size 4.3434 0.6096)
			(layers "F.Cu" "F.Mask" "F.Paste")
			(net "VR_PVCCIN_CPU0_PHASE3")
		)
		(pad "25" smd rect
			(at 1.548384 -1.283208 90)
			(size 2.3368 2.0066)
			(layers "F.Cu" "F.Mask" "F.Paste")
			(net "VR_FET_SW_P12V_STBY_PVCCIN_CPU0")
		)
		(pad "30" smd rect
			(at 2.050034 -2.895092 90)
			(size 0.254 0.7112)
			(layers "F.Cu" "F.Mask" "F.Paste")
			(net "VR_FET_SW_P12V_STBY_PVCCIN_CPU0")
		)
		(pad "31" smd rect
			(at 1.599946 -2.895092 90)
			(size 0.254 0.7112)
			(layers "F.Cu" "F.Mask" "F.Paste")
			(net "Net_363")
		)
		(pad "32" smd rect
			(at 1.150112 -2.895092 90)
			(size 0.254 0.7112)
			(layers "F.Cu" "F.Mask" "F.Paste")
			(net "VR_PVCCIN_CPU0_PH3_PHASE")
		)
		(pad "33" smd rect
			(at 0.700024 -2.895092 90)
			(size 0.254 0.7112)
			(layers "F.Cu" "F.Mask" "F.Paste")
			(net "VR_PVCCIN_CPU0_PH3_BOOT_R")
		)
		(pad "34" smd rect
			(at 0.249936 -2.895092 90)
			(size 0.254 0.7112)
			(layers "F.Cu" "F.Mask" "F.Paste")
			(net "VR_PVCCIN_CPU0_PWM3")
		)
		(pad "35" smd rect
			(at -0.199898 -2.895092 90)
			(size 0.254 0.7112)
			(layers "F.Cu" "F.Mask" "F.Paste")
			(net "P5V_STBY")
		)
		(pad "36" smd rect
			(at -0.649986 -2.895092 90)
			(size 0.254 0.7112)
			(layers "F.Cu" "F.Mask" "F.Paste")
			(net "A_TSENSE_PVCCIN_CPU0")
		)
		(pad "37" smd rect
			(at -1.100074 -2.895092 90)
			(size 0.254 0.7112)
			(layers "F.Cu" "F.Mask" "F.Paste")
			(net "VR_PVCCIN_CPU0_PH3_OCSET")
		)
		(pad "38" smd rect
			(at -1.549908 -2.895092 90)
			(size 0.254 0.7112)
			(layers "F.Cu" "F.Mask" "F.Paste")
			(net "ISENSE_PVCCIN_CPU0_PH3_IMON")
		)
		(pad "39" smd rect
			(at -1.999996 -2.895092 90)
			(size 0.254 0.7112)
			(layers "F.Cu" "F.Mask" "F.Paste")
			(net "VR_PVCCIN_CPU0_AIREF3")
		)
		(pad "40" smd rect
			(at -0.871728 -1.283208 90)
			(size 1.8034 2.0066)
			(layers "F.Cu" "F.Mask" "F.Paste")
			(net "GND")
		)
		(pad "41" smd rect
			(at -1.533906 0.247904 90)
			(size 0.508 0.3556)
			(layers "F.Cu" "F.Mask" "F.Paste")
			(net "TP_PVCCIN_CPU0_PH3_GL_1")
		)
	)
)
